FILE_TYPE = CONNECTIVITY;
{Allegro Design Entry HDL 16.6-p007 (v16-6-112F) 10/10/2012}
"PAGE_NUMBER" = 45;
0"NC";
1"M_B_DQS_DP<17:0>";
2"M_B_DQS_DN<17:0>";
3"M_B_DQ<63:0>";
4"M_B_MA<17:0>";
5"M_B_BG<1:0>";
6"M_B_CLK_DN<3:0>";
7"M_B_ECC<7:0>";
8"M_B_BA<1:0>";
9"M_B_CLK_DP<3:0>";
10"M_B_CS_N<7:0>";
11"M_B_CKE<3:0>";
12"M_B_ODT<3:0>";
13"PVTT_ABC\g";
14"PVDDQ_ABC\g";
15"GND\g";
16"GND\g";
17"PVPP_ABC\g";
18"PVPP_ABC\g";
19"P12V_NVDIMM_ABC\g";
20"GND\g";
21"GND\g";
22"M_B_DQS_DP<10>";
23"M_B_DQS_DP<9>";
24"M_B_DQS_DN<10>";
25"M_B_DQ<59>";
26"M_B_DQS_DN<15>";
27"M_B_DQS_DP<13>";
28"FM_DIMM_EVENT_COD_N";
29"M_B_VREF";
30"TP_CH_B_DIMM_B0_RFU_1";
31"TP_CH_B_DIMM_B0_RFU_0";
32"TP_CH_B_DIMM_B0_RFU_2";
33"M_B_ALERT_N";
34"M_B_ACT_N";
35"SMB_DDR_ABC_VPP_SDA";
36"SMB_DDR_ABC_VPP_SCL";
37"FM_ADR_COMPLETE_ABC_N";
38"M_ABC_RST_N";
39"M_B_PAR";
40"M_B_C<2>";
41"M_B_CS_N<0>";
42"M_B_CKE<0>";
43"M_B_ODT<1>";
44"M_B_ODT<0>";
45"M_B_ECC<6>";
46"M_B_MA<2>";
47"M_B_BA<0>";
48"M_B_BG<1>";
49"M_B_CLK_DP<1>";
50"M_B_CKE<1>";
51"M_B_ECC<0>";
52"M_B_ECC<3>";
53"M_B_ECC<2>";
54"M_B_ECC<5>";
55"M_B_ECC<4>";
56"M_B_ECC<7>";
57"M_B_MA<6>";
58"M_B_MA<5>";
59"M_B_MA<4>";
60"M_B_MA<3>";
61"M_B_MA<1>";
62"M_B_MA<0>";
63"M_B_CS_N<1>";
64"M_B_CS_N<2>";
65"M_B_CS_N<3>";
66"M_B_CLK_DP<0>";
67"M_B_BA<1>";
68"M_B_ECC<1>";
69"M_B_CLK_DN<0>";
70"M_B_CLK_DN<1>";
71"M_B_BG<0>";
72"M_B_DQ<1>";
73"M_B_DQ<0>";
74"M_B_DQ<4>";
75"M_B_DQ<5>";
76"M_B_DQ<2>";
77"M_B_DQ<3>";
78"M_B_DQ<7>";
79"M_B_DQ<9>";
80"M_B_DQ<8>";
81"M_B_DQ<11>";
82"M_B_DQ<10>";
83"M_B_DQ<6>";
84"M_B_DQ<16>";
85"M_B_DQ<14>";
86"M_B_DQ<13>";
87"M_B_DQ<12>";
88"M_B_DQ<15>";
89"M_B_DQ<17>";
90"M_B_DQ<19>";
91"M_B_DQ<18>";
92"M_B_DQ<20>";
93"M_B_DQ<23>";
94"M_B_DQ<21>";
95"M_B_DQ<27>";
96"M_B_DQ<26>";
97"M_B_DQ<22>";
98"M_B_DQ<25>";
99"M_B_DQ<24>";
100"M_B_DQ<31>";
101"M_B_DQ<30>";
102"M_B_DQ<33>";
103"M_B_DQ<29>";
104"M_B_DQ<28>";
105"M_B_DQ<39>";
106"M_B_DQ<37>";
107"M_B_DQ<34>";
108"M_B_DQ<32>";
109"M_B_DQ<35>";
110"M_B_DQ<36>";
111"M_B_DQ<38>";
112"M_B_DQ<41>";
113"M_B_DQ<40>";
114"M_B_DQ<43>";
115"M_B_DQ<46>";
116"M_B_DQ<49>";
117"M_B_DQ<48>";
118"M_B_DQ<51>";
119"M_B_DQ<50>";
120"M_B_DQ<53>";
121"M_B_DQ<42>";
122"M_B_DQ<45>";
123"M_B_DQ<44>";
124"M_B_DQ<47>";
125"M_B_MA<16>";
126"M_B_MA<15>";
127"M_B_MA<14>";
128"M_B_MA<11>";
129"M_B_MA<10>";
130"M_B_MA<9>";
131"M_B_MA<8>";
132"M_B_MA<7>";
133"M_B_MA<17>";
134"M_B_MA<13>";
135"M_B_MA<12>";
136"M_B_DQ<62>";
137"M_B_DQ<63>";
138"M_B_DQ<60>";
139"M_B_DQ<52>";
140"M_B_DQ<55>";
141"M_B_DQ<56>";
142"M_B_DQ<54>";
143"M_B_DQ<57>";
144"M_B_DQ<58>";
145"M_B_DQ<61>";
146"M_B_DQS_DP<6>";
147"M_B_DQS_DN<6>";
148"M_B_DQS_DP<5>";
149"M_B_DQS_DN<5>";
150"M_B_DQS_DP<4>";
151"M_B_DQS_DN<4>";
152"M_B_DQS_DP<3>";
153"M_B_DQS_DN<3>";
154"M_B_DQS_DP<2>";
155"M_B_DQS_DN<2>";
156"M_B_DQS_DP<1>";
157"M_B_DQS_DN<1>";
158"M_B_DQS_DP<0>";
159"M_B_DQS_DN<0>";
160"M_B_DQS_DN<9>";
161"M_B_DQS_DP<8>";
162"M_B_DQS_DN<8>";
163"M_B_DQS_DP<7>";
164"M_B_DQS_DN<7>";
165"M_B_DQS_DN<17>";
166"M_B_DQS_DP<16>";
167"M_B_DQS_DN<16>";
168"M_B_DQS_DP<15>";
169"M_B_DQS_DP<14>";
170"M_B_DQS_DN<14>";
171"M_B_DQS_DN<13>";
172"M_B_DQS_DP<12>";
173"M_B_DQS_DN<12>";
174"M_B_DQS_DP<11>";
175"M_B_DQS_DN<11>";
176"M_B_DQS_DP<17>";
%"TAP"
"6","(700,4850)","2","mstr_standard","I10";
;
CDS_LIB"mstr_standard"
BODY_TYPE"PLUMBING"
HDL_TAP"TRUE";
"B \NAC \NWC"1;
"S \NAC"
BN"14"169;
%"TAP"
"6","(-1700,1850)","2","mstr_standard","I100";
;
CDS_LIB"mstr_standard"
BODY_TYPE"PLUMBING"
HDL_TAP"TRUE";
"B \NAC \NWC"3;
"S \NAC"
BN"9"79;
%"TAP"
"6","(-1700,1950)","2","mstr_standard","I101";
;
CDS_LIB"mstr_standard"
BODY_TYPE"PLUMBING"
HDL_TAP"TRUE";
"B \NAC \NWC"3;
"S \NAC"
BN"11"81;
%"TAP"
"6","(-1700,1900)","2","mstr_standard","I102";
;
CDS_LIB"mstr_standard"
BODY_TYPE"PLUMBING"
HDL_TAP"TRUE";
"B \NAC \NWC"3;
"S \NAC"
BN"8"80;
%"TAP"
"6","(-1700,1700)","2","mstr_standard","I103";
;
CDS_LIB"mstr_standard"
BODY_TYPE"PLUMBING"
HDL_TAP"TRUE";
"B \NAC \NWC"3;
"S \NAC"
BN"4"74;
%"TAP"
"6","(-1700,1750)","2","mstr_standard","I104";
;
CDS_LIB"mstr_standard"
BODY_TYPE"PLUMBING"
HDL_TAP"TRUE";
"B \NAC \NWC"3;
"S \NAC"
BN"7"78;
%"TAP"
"6","(-1700,1800)","2","mstr_standard","I105";
;
CDS_LIB"mstr_standard"
BODY_TYPE"PLUMBING"
HDL_TAP"TRUE";
"B \NAC \NWC"3;
"S \NAC"
BN"6"83;
%"TAP"
"6","(-1700,1650)","2","mstr_standard","I106";
;
CDS_LIB"mstr_standard"
BODY_TYPE"PLUMBING"
HDL_TAP"TRUE";
"B \NAC \NWC"3;
"S \NAC"
BN"5"75;
%"TAP"
"6","(-1700,1600)","2","mstr_standard","I107";
;
CDS_LIB"mstr_standard"
BODY_TYPE"PLUMBING"
HDL_TAP"TRUE";
"B \NAC \NWC"3;
"S \NAC"
BN"2"76;
%"TAP"
"6","(-1700,1500)","2","mstr_standard","I108";
;
CDS_LIB"mstr_standard"
BODY_TYPE"PLUMBING"
HDL_TAP"TRUE";
"B \NAC \NWC"3;
"S \NAC"
BN"0"73;
%"TAP"
"6","(-1700,1550)","2","mstr_standard","I109";
;
CDS_LIB"mstr_standard"
BODY_TYPE"PLUMBING"
HDL_TAP"TRUE";
"B \NAC \NWC"3;
"S \NAC"
BN"3"77;
%"TAP"
"6","(-1700,1450)","2","mstr_standard","I110";
;
CDS_LIB"mstr_standard"
BODY_TYPE"PLUMBING"
HDL_TAP"TRUE";
"B \NAC \NWC"3;
"S \NAC"
BN"1"72;
%"SCONN288_H44441004"
"1","(-2450,2950)","0","mstr_sconn","I111";
;
CDS_SEC"1"
MATERIAL"SCONN"
PART_NUMBER"H44441-004"
LOCATION"J4G2"
PACK_TYPE"PIP"
BOM_COST"MEM"
CDS_LIB"mstr_sconn"
SEC_TYPE"PIP"
SEC"1"
CDS_LOCATION"J4G2"
ROOM"DDR4_CH_B";
"DQ<63>"
$PN"280"136;
"DQ<62>"
$PN"135"137;
"DQ<61>"
$PN"273"138;
"DQ<5>"
$PN"148"74;
"DQ<4>"
$PN"3"75;
"DQ<3>"
$PN"157"76;
"DQ<2>"
$PN"12"77;
"DQ<47>"
$PN"258"115;
"DQ<48>"
$PN"119"116;
"DQ<49>"
$PN"264"117;
"DQ<50>"
$PN"126"118;
"DQ<51>"
$PN"271"119;
"DQ<52>"
$PN"117"120;
"DQ<53>"
$PN"262"139;
"DQ<54>"
$PN"124"140;
"DQ<58>"
$PN"137"25;
"DQ<57>"
$PN"275"141;
"SAVE_N_NC"
$PN"230"37;
"RFU<1>"
$PN"227"30;
"RFU<0>"
$PN"205"31;
"DQ<17>"
$PN"172"84;
"DQ<15>"
$PN"166"85;
"DQ<26>"
$PN"45"95;
"DQ<27>"
$PN"190"96;
"S0_N"
$PN"84"41;
"CKE<0>"
$PN"60"42;
"ODT<1>"
$PN"91"43;
"ODT<0>"
$PN"87"44;
"CB<7>"
$PN"199"45;
"A16_RAS_N"
$PN"82"125;
"A15_CAS_N"
$PN"86"126;
"A14_WE_N"
$PN"228"127;
"A11"
$PN"210"128;
"A10"
$PN"225"129;
"DQ<38>"
$PN"102"105;
"DQ<36>"
$PN"95"106;
"DQ<35>"
$PN"249"107;
"A2"
$PN"216"46;
"ALERT_N"
$PN"208"33;
"ACT_N"
$PN"62"34;
"DQ<0>"
$PN"5"72;
"DQ<1>"
$PN"150"73;
"SA<1>"
$PN"140"18;
"SA<2>"
$PN"238"15;
"VDDSPD"
$PN"284"18;
"SA<0>"
$PN"139"15;
"BA<0>"
$PN"81"47;
"BG<1>"
$PN"207"48;
"BG<0>"
$PN"63"71;
"CK1P"
$PN"218"49;
"VREFCA"
$PN"146"29;
"SDA"
$PN"285"35;
"SCL"
$PN"141"36;
"RFU<2>"
$PN"144"32;
"RESET_N"
$PN"58"38;
"PAR"
$PN"222"39;
"EVENT_N"
$PN"78"28;
"DQ<6>"
$PN"10"78;
"DQ<7>"
$PN"155"83;
"DQ<8>"
$PN"16"79;
"DQ<9>"
$PN"161"80;
"DQ<10>"
$PN"23"81;
"DQ<11>"
$PN"168"82;
"DQ<12>"
$PN"14"86;
"DQ<13>"
$PN"159"87;
"DQ<14>"
$PN"21"88;
"DQ<16>"
$PN"27"89;
"DQ<18>"
$PN"34"90;
"DQ<19>"
$PN"179"91;
"DQ<20>"
$PN"25"94;
"DQ<21>"
$PN"170"92;
"DQ<22>"
$PN"32"93;
"DQ<23>"
$PN"177"97;
"DQ<24>"
$PN"38"98;
"DQ<25>"
$PN"183"99;
"DQ<30>"
$PN"43"100;
"DQ<31>"
$PN"188"101;
"DQ<32>"
$PN"97"102;
"DQ<33>"
$PN"242"108;
"DQ<34>"
$PN"104"109;
"DQ<37>"
$PN"240"110;
"DQ<39>"
$PN"247"111;
"DQ<40>"
$PN"108"112;
"DQ<41>"
$PN"253"113;
"DQ<42>"
$PN"115"114;
"DQ<43>"
$PN"260"121;
"DQ<44>"
$PN"106"122;
"DQ<45>"
$PN"251"123;
"DQ<46>"
$PN"113"124;
"DQ<55>"
$PN"269"142;
"DQ<56>"
$PN"130"143;
"DQ<59>"
$PN"282"144;
"DQ<60>"
$PN"128"145;
"CKE<1>"
$PN"203"50;
"CK0N"
$PN"75"69;
"CB<0>"
$PN"49"68;
"CB<1>"
$PN"194"51;
"CB<2>"
$PN"56"52;
"CB<3>"
$PN"201"53;
"CB<4>"
$PN"47"54;
"CB<5>"
$PN"192"55;
"CB<6>"
$PN"54"56;
"A9"
$PN"66"130;
"A8"
$PN"68"131;
"A7"
$PN"211"132;
"A6"
$PN"69"57;
"A5"
$PN"213"58;
"A4"
$PN"214"59;
"A3"
$PN"71"60;
"A17"
$PN"234"133;
"A13"
$PN"232"134;
"A12"
$PN"65"135;
"A1"
$PN"72"61;
"A0"
$PN"79"62;
"C<2>"
$PN"235"40;
"DQ<28>"
$PN"36"103;
"DQ<29>"
$PN"181"104;
"S1_N"
$PN"89"63;
"S2_N_C<0>"
$PN"93"64;
"S3_N_C<1>"
$PN"237"65;
"CK0P"
$PN"74"66;
"CK1N"
$PN"219"70;
"BA<1>"
$PN"224"67;
%"TAP"
"6","(-3200,4600)","0","mstr_standard","I112";
;
CDS_LIB"mstr_standard"
BODY_TYPE"PLUMBING"
HDL_TAP"TRUE";
"B \NAC \NWC"4;
"S \NAC"
BN"17"133;
%"TAP"
"6","(-3200,4550)","0","mstr_standard","I113";
;
CDS_LIB"mstr_standard"
BODY_TYPE"PLUMBING"
HDL_TAP"TRUE";
"B \NAC \NWC"4;
"S \NAC"
BN"16"125;
%"TAP"
"6","(-3200,4500)","0","mstr_standard","I114";
;
CDS_LIB"mstr_standard"
BODY_TYPE"PLUMBING"
HDL_TAP"TRUE";
"B \NAC \NWC"4;
"S \NAC"
BN"15"126;
%"TAP"
"6","(-3200,4450)","0","mstr_standard","I115";
;
CDS_LIB"mstr_standard"
BODY_TYPE"PLUMBING"
HDL_TAP"TRUE";
"B \NAC \NWC"4;
"S \NAC"
BN"14"127;
%"TAP"
"6","(-3200,4400)","0","mstr_standard","I116";
;
CDS_LIB"mstr_standard"
BODY_TYPE"PLUMBING"
HDL_TAP"TRUE";
"B \NAC \NWC"4;
"S \NAC"
BN"13"134;
%"TAP"
"6","(-3200,4350)","0","mstr_standard","I117";
;
CDS_LIB"mstr_standard"
BODY_TYPE"PLUMBING"
HDL_TAP"TRUE";
"B \NAC \NWC"4;
"S \NAC"
BN"12"135;
%"TAP"
"6","(-3200,4300)","0","mstr_standard","I118";
;
CDS_LIB"mstr_standard"
BODY_TYPE"PLUMBING"
HDL_TAP"TRUE";
"B \NAC \NWC"4;
"S \NAC"
BN"11"128;
%"TAP"
"6","(-3200,4250)","0","mstr_standard","I119";
;
CDS_LIB"mstr_standard"
BODY_TYPE"PLUMBING"
HDL_TAP"TRUE";
"B \NAC \NWC"4;
"S \NAC"
BN"10"129;
%"PVTT_ABC"
"1","(-800,2700)","0","mstr_symbols","I12";
;
VOLTAGE"0.6V"
BOM_COST"MEM"
CDS_LIB"mstr_symbols"
BODY_TYPE"PLUMBING"
ROOM"DDR4_CH_A"
HDL_POWER"PVTT_ABC";
"G\NAC"13;
%"TAP"
"6","(-3200,4200)","0","mstr_standard","I120";
;
CDS_LIB"mstr_standard"
BODY_TYPE"PLUMBING"
HDL_TAP"TRUE";
"B \NAC \NWC"4;
"S \NAC"
BN"9"130;
%"TAP"
"6","(-3200,4150)","0","mstr_standard","I121";
;
CDS_LIB"mstr_standard"
BODY_TYPE"PLUMBING"
HDL_TAP"TRUE";
"B \NAC \NWC"4;
"S \NAC"
BN"8"131;
%"TAP"
"6","(-3200,4100)","0","mstr_standard","I122";
;
CDS_LIB"mstr_standard"
BODY_TYPE"PLUMBING"
HDL_TAP"TRUE";
"B \NAC \NWC"4;
"S \NAC"
BN"7"132;
%"TAP"
"6","(-3200,4050)","0","mstr_standard","I123";
;
CDS_LIB"mstr_standard"
BODY_TYPE"PLUMBING"
HDL_TAP"TRUE";
"B \NAC \NWC"4;
"S \NAC"
BN"6"57;
%"TAP"
"6","(-3200,4000)","0","mstr_standard","I124";
;
CDS_LIB"mstr_standard"
BODY_TYPE"PLUMBING"
HDL_TAP"TRUE";
"B \NAC \NWC"4;
"S \NAC"
BN"5"58;
%"TAP"
"6","(-3200,3950)","0","mstr_standard","I125";
;
CDS_LIB"mstr_standard"
BODY_TYPE"PLUMBING"
HDL_TAP"TRUE";
"B \NAC \NWC"4;
"S \NAC"
BN"4"59;
%"TAP"
"6","(-3200,3900)","0","mstr_standard","I126";
;
CDS_LIB"mstr_standard"
BODY_TYPE"PLUMBING"
HDL_TAP"TRUE";
"B \NAC \NWC"4;
"S \NAC"
BN"3"60;
%"TAP"
"6","(-3200,3850)","0","mstr_standard","I128";
;
CDS_LIB"mstr_standard"
BODY_TYPE"PLUMBING"
HDL_TAP"TRUE";
"B \NAC \NWC"4;
"S \NAC"
BN"2"46;
%"TAP"
"6","(-3200,3800)","0","mstr_standard","I129";
;
CDS_LIB"mstr_standard"
BODY_TYPE"PLUMBING"
HDL_TAP"TRUE";
"B \NAC \NWC"4;
"S \NAC"
BN"1"61;
%"PVDDQ_ABC"
"1","(-1025,2550)","0","mstr_symbols","I13";
;
VOLTAGE"1.2V"
BOM_COST"MEM"
CDS_LIB"mstr_symbols"
BODY_TYPE"PLUMBING"
ROOM"DDR4_CH_A"
HDL_POWER"PVDDQ_ABC";
"G\NAC"14;
%"TAP"
"6","(-3200,3750)","0","mstr_standard","I130";
;
CDS_LIB"mstr_standard"
BODY_TYPE"PLUMBING"
HDL_TAP"TRUE";
"B \NAC \NWC"4;
"S \NAC"
BN"0"62;
%"TAP"
"6","(-3200,3650)","0","mstr_standard","I131";
;
CDS_LIB"mstr_standard"
BODY_TYPE"PLUMBING"
HDL_TAP"TRUE";
"B \NAC \NWC"8;
"S \NAC"
BN"1"67;
%"TAP"
"6","(-3200,3600)","0","mstr_standard","I132";
;
CDS_LIB"mstr_standard"
BODY_TYPE"PLUMBING"
HDL_TAP"TRUE";
"B \NAC \NWC"8;
"S \NAC"
BN"0"47;
%"TAP"
"6","(-3200,3500)","0","mstr_standard","I133";
;
CDS_LIB"mstr_standard"
BODY_TYPE"PLUMBING"
HDL_TAP"TRUE";
"B \NAC \NWC"5;
"S \NAC"
BN"0"71;
%"TAP"
"6","(-3200,3550)","0","mstr_standard","I134";
;
CDS_LIB"mstr_standard"
BODY_TYPE"PLUMBING"
HDL_TAP"TRUE";
"B \NAC \NWC"5;
"S \NAC"
BN"1"48;
%"TAP"
"6","(-3200,2550)","0","mstr_standard","I138";
;
CDS_LIB"mstr_standard"
BODY_TYPE"PLUMBING"
HDL_TAP"TRUE";
"B \NAC \NWC"7;
"S \NAC"
BN"6"45;
%"TAP"
"6","(-3200,2500)","0","mstr_standard","I139";
;
CDS_LIB"mstr_standard"
BODY_TYPE"PLUMBING"
HDL_TAP"TRUE";
"B \NAC \NWC"7;
"S \NAC"
BN"7"56;
%"TAP"
"6","(900,4600)","2","mstr_standard","I14";
;
CDS_LIB"mstr_standard"
BODY_TYPE"PLUMBING"
HDL_TAP"TRUE";
"B \NAC \NWC"2;
"S \NAC"
BN"12"173;
%"TAP"
"6","(-3200,2450)","0","mstr_standard","I140";
;
CDS_LIB"mstr_standard"
BODY_TYPE"PLUMBING"
HDL_TAP"TRUE";
"B \NAC \NWC"7;
"S \NAC"
BN"4"55;
%"TAP"
"6","(-3200,2400)","0","mstr_standard","I141";
;
CDS_LIB"mstr_standard"
BODY_TYPE"PLUMBING"
HDL_TAP"TRUE";
"B \NAC \NWC"7;
"S \NAC"
BN"5"54;
%"TAP"
"6","(-3200,2350)","0","mstr_standard","I142";
;
CDS_LIB"mstr_standard"
BODY_TYPE"PLUMBING"
HDL_TAP"TRUE";
"B \NAC \NWC"7;
"S \NAC"
BN"2"53;
%"TAP"
"6","(-3200,2300)","0","mstr_standard","I143";
;
CDS_LIB"mstr_standard"
BODY_TYPE"PLUMBING"
HDL_TAP"TRUE";
"B \NAC \NWC"7;
"S \NAC"
BN"3"52;
%"TAP"
"6","(-3200,2250)","0","mstr_standard","I144";
;
CDS_LIB"mstr_standard"
BODY_TYPE"PLUMBING"
HDL_TAP"TRUE";
"B \NAC \NWC"7;
"S \NAC"
BN"0"51;
%"TAP"
"6","(-3200,2200)","0","mstr_standard","I145";
;
CDS_LIB"mstr_standard"
BODY_TYPE"PLUMBING"
HDL_TAP"TRUE";
"B \NAC \NWC"7;
"S \NAC"
BN"1"68;
%"TAP"
"6","(900,4700)","2","mstr_standard","I15";
;
CDS_LIB"mstr_standard"
BODY_TYPE"PLUMBING"
HDL_TAP"TRUE";
"B \NAC \NWC"2;
"S \NAC"
BN"13"171;
%"TAP"
"6","(-3200,2700)","0","mstr_standard","I152";
;
CDS_LIB"mstr_standard"
BODY_TYPE"PLUMBING"
HDL_TAP"TRUE";
"B \NAC \NWC"12;
"S \NAC"
BN"1"43;
%"TAP"
"6","(-3200,2650)","0","mstr_standard","I153";
;
CDS_LIB"mstr_standard"
BODY_TYPE"PLUMBING"
HDL_TAP"TRUE";
"B \NAC \NWC"12;
"S \NAC"
BN"0"44;
%"TAP"
"6","(-3200,2850)","0","mstr_standard","I155";
;
CDS_LIB"mstr_standard"
BODY_TYPE"PLUMBING"
HDL_TAP"TRUE";
"B \NAC \NWC"11;
"S \NAC"
BN"1"50;
%"TAP"
"6","(-3200,2800)","0","mstr_standard","I156";
;
CDS_LIB"mstr_standard"
BODY_TYPE"PLUMBING"
HDL_TAP"TRUE";
"B \NAC \NWC"11;
"S \NAC"
BN"0"42;
%"TAP"
"6","(-3200,3100)","0","mstr_standard","I158";
;
CDS_LIB"mstr_standard"
BODY_TYPE"PLUMBING"
HDL_TAP"TRUE";
"B \NAC \NWC"10;
"S \NAC"
BN"3"65;
%"TAP"
"6","(700,4750)","2","mstr_standard","I16";
;
CDS_LIB"mstr_standard"
BODY_TYPE"PLUMBING"
HDL_TAP"TRUE";
"B \NAC \NWC"1;
"S \NAC"
BN"13"27;
%"TAP"
"6","(-3200,3050)","0","mstr_standard","I160";
;
CDS_LIB"mstr_standard"
BODY_TYPE"PLUMBING"
HDL_TAP"TRUE";
"B \NAC \NWC"10;
"S \NAC"
BN"2"64;
%"TAP"
"6","(-3200,3000)","0","mstr_standard","I161";
;
CDS_LIB"mstr_standard"
BODY_TYPE"PLUMBING"
HDL_TAP"TRUE";
"B \NAC \NWC"10;
"S \NAC"
BN"1"63;
%"TAP"
"6","(-3200,2950)","0","mstr_standard","I162";
;
CDS_LIB"mstr_standard"
BODY_TYPE"PLUMBING"
HDL_TAP"TRUE";
"B \NAC \NWC"10;
"S \NAC"
BN"0"41;
%"TAP"
"6","(-3400,3350)","0","mstr_standard","I163";
;
CDS_LIB"mstr_standard"
BODY_TYPE"PLUMBING"
HDL_TAP"TRUE";
"B \NAC \NWC"6;
"S \NAC"
BN"1"70;
%"TAP"
"6","(-3400,3250)","0","mstr_standard","I164";
;
CDS_LIB"mstr_standard"
BODY_TYPE"PLUMBING"
HDL_TAP"TRUE";
"B \NAC \NWC"6;
"S \NAC"
BN"0"69;
%"TAP"
"6","(-3200,3300)","0","mstr_standard","I165";
;
CDS_LIB"mstr_standard"
BODY_TYPE"PLUMBING"
HDL_TAP"TRUE";
"B \NAC \NWC"9;
"S \NAC"
BN"0"66;
%"TAP"
"6","(-3200,3400)","0","mstr_standard","I166";
;
CDS_LIB"mstr_standard"
BODY_TYPE"PLUMBING"
HDL_TAP"TRUE";
"B \NAC \NWC"9;
"S \NAC"
BN"1"49;
%"SCONN288_H44441004"
"4","(50,2000)","0","mstr_sconn","I169";
;
CDS_SEC"4"
LOCATION"J4G2"
PART_NUMBER"H44441-004"
MATERIAL"SCONN"
PACK_TYPE"PIP"
BOM_COST"MEM"
CDS_LIB"mstr_sconn"
SEC_TYPE"PIP"
SEC"4"
CDS_LOCATION"J4G2"
ROOM"DDR4_CH_B";
"VPP<4>"
$PN"142"17;
"VTT<1>"
$PN"77"13;
"VPP<0>"
$PN"287"17;
"VPP<1>"
$PN"286"17;
"VPP<2>"
$PN"288"17;
"VPP<3>"
$PN"143"17;
"VDD<1>"
$PN"233"14;
"VDD<2>"
$PN"231"14;
"VDD<3>"
$PN"229"14;
"VDD<4>"
$PN"226"14;
"VDD<5>"
$PN"223"14;
"VDD<7>"
$PN"217"14;
"VDD<8>"
$PN"215"14;
"VDD<9>"
$PN"212"14;
"VDD<11>"
$PN"206"14;
"VDD<12>"
$PN"204"14;
"VDD<14>"
$PN"90"14;
"VDD<15>"
$PN"88"14;
"VDD<17>"
$PN"83"14;
"VDD<18>"
$PN"80"14;
"VDD<20>"
$PN"73"14;
"VDD<21>"
$PN"70"14;
"VDD<22>"
$PN"67"14;
"VDD<24>"
$PN"61"14;
"12V<0>"
$PN"145"19;
"12V<1>"
$PN"1"19;
"VTT<0>"
$PN"221"13;
"VDD<25>"
$PN"59"14;
"VDD<23>"
$PN"64"14;
"VDD<19>"
$PN"76"14;
"VDD<16>"
$PN"85"14;
"VDD<13>"
$PN"92"14;
"VDD<10>"
$PN"209"14;
"VDD<6>"
$PN"220"14;
"VDD<0>"
$PN"236"14;
%"TAP"
"6","(700,4650)","2","mstr_standard","I17";
;
CDS_LIB"mstr_standard"
BODY_TYPE"PLUMBING"
HDL_TAP"TRUE";
"B \NAC \NWC"1;
"S \NAC"
BN"12"172;
%"GND"
"1","(-5050,1600)","2","mstr_symbols","I174";
;
VOLTAGE"0"
BOM_COST"MEM"
CDS_LIB"mstr_symbols"
SIZE"1B"
BODY_TYPE"PLUMBING"
ROOM"DDR4_CH_A"
HDL_POWER"GND";
"A\NAC"15;
%"GND"
"1","(-4600,1000)","0","mstr_symbols","I178";
;
VOLTAGE"0"
CDS_LIB"mstr_symbols"
SIZE"1B"
BOM_COST"MEM"
BODY_TYPE"PLUMBING"
ROOM"DDR4_CH_A"
HDL_POWER"GND";
"A\NAC"16;
%"CAP_A"
"1","(-4600,1250)","2","dev_discrete","I179";
;
CDS_SEC"1"
LOCATION"C4G3"
PART_NUMBER"A36096-045"
VALUE"0.01UF"
TOLERANCE"10%"
VOLTAGE"25V"
MATERIAL"X7R"
PACK_TYPE"0402V"
CDS_LOCATION"C4G3"
BOM_COST"MEM"
CDS_LIB"dev_discrete"
ROOM"DDR4_CH_A"
SEC"1"
SEC_TYPE"0402V";
"B"
$PN"2"16;
"A"
$PN"1"29;
%"TAP"
"6","(700,4550)","2","mstr_standard","I18";
;
CDS_LIB"mstr_standard"
BODY_TYPE"PLUMBING"
HDL_TAP"TRUE";
"B \NAC \NWC"1;
"S \NAC"
BN"11"174;
%"PVPP_ABC"
"1","(-650,3000)","0","mstr_symbols","I180";
;
VOLTAGE"2.5V"
BOM_COST"MEM"
CDS_LIB"mstr_symbols"
BODY_TYPE"PLUMBING"
ROOM"DDR4_CH_A"
HDL_POWER"PVPP_ABC";
"G\NAC"17;
%"PVPP_ABC"
"1","(-5050,1950)","0","mstr_symbols","I181";
;
VOLTAGE"2.5V"
BOM_COST"MEM"
CDS_LIB"mstr_symbols"
BODY_TYPE"PLUMBING"
ROOM"DDR4_CH_A"
HDL_POWER"PVPP_ABC";
"G\NAC"18;
%"P12V_NVDIMM_ABC"
"1","(750,3075)","0","mstr_symbols","I183";
;
VOLTAGE"12.0"
CDS_LIB"mstr_symbols"
BODY_TYPE"PLUMBING"
HDL_POWER"P12V_NVDIMM_ABC";
"G\NAC"19;
%"TAP"
"6","(900,4400)","2","mstr_standard","I19";
;
CDS_LIB"mstr_standard"
BODY_TYPE"PLUMBING"
HDL_TAP"TRUE";
"B \NAC \NWC"2;
"S \NAC"
BN"10"24;
%"TAP"
"6","(900,4500)","2","mstr_standard","I20";
;
CDS_LIB"mstr_standard"
BODY_TYPE"PLUMBING"
HDL_TAP"TRUE";
"B \NAC \NWC"2;
"S \NAC"
BN"11"175;
%"TAP"
"6","(900,4300)","2","mstr_standard","I21";
;
CDS_LIB"mstr_standard"
BODY_TYPE"PLUMBING"
HDL_TAP"TRUE";
"B \NAC \NWC"2;
"S \NAC"
BN"9"160;
%"TAP"
"6","(700,4450)","2","mstr_standard","I22";
;
CDS_LIB"mstr_standard"
BODY_TYPE"PLUMBING"
HDL_TAP"TRUE";
"B \NAC \NWC"1;
"S \NAC"
BN"10"22;
%"TAP"
"6","(700,4350)","2","mstr_standard","I23";
;
CDS_LIB"mstr_standard"
BODY_TYPE"PLUMBING"
HDL_TAP"TRUE";
"B \NAC \NWC"1;
"S \NAC"
BN"9"23;
%"TAP"
"6","(900,4100)","2","mstr_standard","I24";
;
CDS_LIB"mstr_standard"
BODY_TYPE"PLUMBING"
HDL_TAP"TRUE";
"B \NAC \NWC"2;
"S \NAC"
BN"7"164;
%"TAP"
"6","(900,4200)","2","mstr_standard","I25";
;
CDS_LIB"mstr_standard"
BODY_TYPE"PLUMBING"
HDL_TAP"TRUE";
"B \NAC \NWC"2;
"S \NAC"
BN"8"162;
%"TAP"
"6","(700,4250)","2","mstr_standard","I26";
;
CDS_LIB"mstr_standard"
BODY_TYPE"PLUMBING"
HDL_TAP"TRUE";
"B \NAC \NWC"1;
"S \NAC"
BN"8"161;
%"TAP"
"6","(700,4150)","2","mstr_standard","I27";
;
CDS_LIB"mstr_standard"
BODY_TYPE"PLUMBING"
HDL_TAP"TRUE";
"B \NAC \NWC"1;
"S \NAC"
BN"7"163;
%"TAP"
"6","(700,4050)","2","mstr_standard","I28";
;
CDS_LIB"mstr_standard"
BODY_TYPE"PLUMBING"
HDL_TAP"TRUE";
"B \NAC \NWC"1;
"S \NAC"
BN"6"146;
%"TAP"
"6","(900,3900)","2","mstr_standard","I29";
;
CDS_LIB"mstr_standard"
BODY_TYPE"PLUMBING"
HDL_TAP"TRUE";
"B \NAC \NWC"2;
"S \NAC"
BN"5"149;
%"TAP"
"6","(900,5100)","2","mstr_standard","I3";
;
CDS_LIB"mstr_standard"
BODY_TYPE"PLUMBING"
HDL_TAP"TRUE";
"B \NAC \NWC"2;
"S \NAC"
BN"17"165;
%"TAP"
"6","(900,4000)","2","mstr_standard","I30";
;
CDS_LIB"mstr_standard"
BODY_TYPE"PLUMBING"
HDL_TAP"TRUE";
"B \NAC \NWC"2;
"S \NAC"
BN"6"147;
%"TAP"
"6","(900,3800)","2","mstr_standard","I31";
;
CDS_LIB"mstr_standard"
BODY_TYPE"PLUMBING"
HDL_TAP"TRUE";
"B \NAC \NWC"2;
"S \NAC"
BN"4"151;
%"TAP"
"6","(700,3950)","2","mstr_standard","I32";
;
CDS_LIB"mstr_standard"
BODY_TYPE"PLUMBING"
HDL_TAP"TRUE";
"B \NAC \NWC"1;
"S \NAC"
BN"5"148;
%"TAP"
"6","(700,3850)","2","mstr_standard","I33";
;
CDS_LIB"mstr_standard"
BODY_TYPE"PLUMBING"
HDL_TAP"TRUE";
"B \NAC \NWC"1;
"S \NAC"
BN"4"150;
%"TAP"
"6","(700,3750)","2","mstr_standard","I34";
;
CDS_LIB"mstr_standard"
BODY_TYPE"PLUMBING"
HDL_TAP"TRUE";
"B \NAC \NWC"1;
"S \NAC"
BN"3"152;
%"TAP"
"6","(900,3500)","2","mstr_standard","I35";
;
CDS_LIB"mstr_standard"
BODY_TYPE"PLUMBING"
HDL_TAP"TRUE";
"B \NAC \NWC"2;
"S \NAC"
BN"1"157;
%"TAP"
"6","(900,3600)","2","mstr_standard","I36";
;
CDS_LIB"mstr_standard"
BODY_TYPE"PLUMBING"
HDL_TAP"TRUE";
"B \NAC \NWC"2;
"S \NAC"
BN"2"155;
%"TAP"
"6","(900,3700)","2","mstr_standard","I37";
;
CDS_LIB"mstr_standard"
BODY_TYPE"PLUMBING"
HDL_TAP"TRUE";
"B \NAC \NWC"2;
"S \NAC"
BN"3"153;
%"TAP"
"6","(700,3650)","2","mstr_standard","I38";
;
CDS_LIB"mstr_standard"
BODY_TYPE"PLUMBING"
HDL_TAP"TRUE";
"B \NAC \NWC"1;
"S \NAC"
BN"2"154;
%"TAP"
"6","(700,3550)","2","mstr_standard","I39";
;
CDS_LIB"mstr_standard"
BODY_TYPE"PLUMBING"
HDL_TAP"TRUE";
"B \NAC \NWC"1;
"S \NAC"
BN"1"156;
%"TAP"
"6","(700,5150)","2","mstr_standard","I4";
;
CDS_LIB"mstr_standard"
BODY_TYPE"PLUMBING"
HDL_TAP"TRUE";
"B \NAC \NWC"1;
"S \NAC"
BN"17"176;
%"TAP"
"6","(900,3400)","2","mstr_standard","I40";
;
CDS_LIB"mstr_standard"
BODY_TYPE"PLUMBING"
HDL_TAP"TRUE";
"B \NAC \NWC"2;
"S \NAC"
BN"0"159;
%"TAP"
"6","(700,3450)","2","mstr_standard","I41";
;
CDS_LIB"mstr_standard"
BODY_TYPE"PLUMBING"
HDL_TAP"TRUE";
"B \NAC \NWC"1;
"S \NAC"
BN"0"158;
%"GND"
"1","(2500,1300)","2","mstr_symbols","I42";
;
VOLTAGE"0"
BOM_COST"MEM"
CDS_LIB"mstr_symbols"
SIZE"1B"
BODY_TYPE"PLUMBING"
ROOM"DDR4_CH_A"
HDL_POWER"GND";
"A\NAC"20;
%"SCONN288_H44441004"
"3","(1800,2600)","0","mstr_sconn","I43";
;
CDS_SEC"3"
LOCATION"J4G2"
PART_NUMBER"H44441-004"
MATERIAL"SCONN"
PACK_TYPE"PIP"
BOM_COST"MEM"
CDS_LIB"mstr_sconn"
SEC_TYPE"PIP"
SEC"3"
CDS_LOCATION"J4G2"
ROOM"DDR4_CH_B";
"VSS<93>"
$PN"2"21;
"VSS<92>"
$PN"4"21;
"VSS<91>"
$PN"6"21;
"VSS<90>"
$PN"9"21;
"VSS<89>"
$PN"11"21;
"VSS<88>"
$PN"13"21;
"VSS<0>"
$PN"283"20;
"VSS<1>"
$PN"281"20;
"VSS<2>"
$PN"279"20;
"VSS<3>"
$PN"276"20;
"VSS<4>"
$PN"274"20;
"VSS<5>"
$PN"272"20;
"VSS<6>"
$PN"270"20;
"VSS<7>"
$PN"268"20;
"VSS<8>"
$PN"265"20;
"VSS<9>"
$PN"263"20;
"VSS<10>"
$PN"261"20;
"VSS<11>"
$PN"259"20;
"VSS<12>"
$PN"257"20;
"VSS<13>"
$PN"254"20;
"VSS<14>"
$PN"252"20;
"VSS<15>"
$PN"250"20;
"VSS<16>"
$PN"248"20;
"VSS<17>"
$PN"246"20;
"VSS<18>"
$PN"243"20;
"VSS<19>"
$PN"241"20;
"VSS<20>"
$PN"239"20;
"VSS<21>"
$PN"202"20;
"VSS<22>"
$PN"200"20;
"VSS<23>"
$PN"198"20;
"VSS<24>"
$PN"195"20;
"VSS<25>"
$PN"193"20;
"VSS<26>"
$PN"191"20;
"VSS<27>"
$PN"189"20;
"VSS<28>"
$PN"187"20;
"VSS<29>"
$PN"184"20;
"VSS<30>"
$PN"182"20;
"VSS<31>"
$PN"180"20;
"VSS<32>"
$PN"178"20;
"VSS<33>"
$PN"176"20;
"VSS<34>"
$PN"173"20;
"VSS<35>"
$PN"171"20;
"VSS<36>"
$PN"169"20;
"VSS<37>"
$PN"167"20;
"VSS<38>"
$PN"165"20;
"VSS<39>"
$PN"162"20;
"VSS<40>"
$PN"160"20;
"VSS<41>"
$PN"158"20;
"VSS<42>"
$PN"156"20;
"VSS<43>"
$PN"154"20;
"VSS<44>"
$PN"151"20;
"VSS<47>"
$PN"138"21;
"VSS<48>"
$PN"136"21;
"VSS<49>"
$PN"134"21;
"VSS<50>"
$PN"131"21;
"VSS<51>"
$PN"129"21;
"VSS<52>"
$PN"127"21;
"VSS<53>"
$PN"125"21;
"VSS<54>"
$PN"123"21;
"VSS<55>"
$PN"120"21;
"VSS<56>"
$PN"118"21;
"VSS<57>"
$PN"116"21;
"VSS<58>"
$PN"114"21;
"VSS<59>"
$PN"112"21;
"VSS<60>"
$PN"109"21;
"VSS<61>"
$PN"107"21;
"VSS<62>"
$PN"105"21;
"VSS<63>"
$PN"103"21;
"VSS<64>"
$PN"101"21;
"VSS<65>"
$PN"98"21;
"VSS<66>"
$PN"96"21;
"VSS<67>"
$PN"94"21;
"VSS<68>"
$PN"57"21;
"VSS<69>"
$PN"55"21;
"VSS<70>"
$PN"53"21;
"VSS<71>"
$PN"50"21;
"VSS<72>"
$PN"48"21;
"VSS<73>"
$PN"46"21;
"VSS<74>"
$PN"44"21;
"VSS<75>"
$PN"42"21;
"VSS<76>"
$PN"39"21;
"VSS<77>"
$PN"37"21;
"VSS<78>"
$PN"35"21;
"VSS<79>"
$PN"33"21;
"VSS<80>"
$PN"31"21;
"VSS<81>"
$PN"28"21;
"VSS<82>"
$PN"26"21;
"VSS<83>"
$PN"24"21;
"VSS<84>"
$PN"22"21;
"VSS<85>"
$PN"20"21;
"VSS<86>"
$PN"17"21;
"VSS<87>"
$PN"15"21;
"VSS<45>"
$PN"149"20;
"VSS<46>"
$PN"147"20;
%"GND"
"1","(1100,1300)","2","mstr_symbols","I44";
;
VOLTAGE"0"
BOM_COST"MEM"
CDS_LIB"mstr_symbols"
SIZE"1B"
BODY_TYPE"PLUMBING"
ROOM"DDR4_CH_A"
HDL_POWER"GND";
"A\NAC"21;
%"TAP"
"6","(-1700,4600)","2","mstr_standard","I46";
;
CDS_LIB"mstr_standard"
BODY_TYPE"PLUMBING"
HDL_TAP"TRUE";
"B \NAC \NWC"3;
"S \NAC"
BN"62"136;
%"TAP"
"6","(-1700,4550)","2","mstr_standard","I47";
;
CDS_LIB"mstr_standard"
BODY_TYPE"PLUMBING"
HDL_TAP"TRUE";
"B \NAC \NWC"3;
"S \NAC"
BN"63"137;
%"TAP"
"6","(-1700,4400)","2","mstr_standard","I48";
;
CDS_LIB"mstr_standard"
BODY_TYPE"PLUMBING"
HDL_TAP"TRUE";
"B \NAC \NWC"3;
"S \NAC"
BN"58"144;
%"TAP"
"6","(-1700,4450)","2","mstr_standard","I49";
;
CDS_LIB"mstr_standard"
BODY_TYPE"PLUMBING"
HDL_TAP"TRUE";
"B \NAC \NWC"3;
"S \NAC"
BN"61"145;
%"TAP"
"6","(700,5050)","2","mstr_standard","I5";
;
CDS_LIB"mstr_standard"
BODY_TYPE"PLUMBING"
HDL_TAP"TRUE";
"B \NAC \NWC"1;
"S \NAC"
BN"16"166;
%"TAP"
"6","(-1700,4500)","2","mstr_standard","I50";
;
CDS_LIB"mstr_standard"
BODY_TYPE"PLUMBING"
HDL_TAP"TRUE";
"B \NAC \NWC"3;
"S \NAC"
BN"60"138;
%"TAP"
"6","(-1700,4300)","2","mstr_standard","I51";
;
CDS_LIB"mstr_standard"
BODY_TYPE"PLUMBING"
HDL_TAP"TRUE";
"B \NAC \NWC"3;
"S \NAC"
BN"56"141;
%"TAP"
"6","(-1700,4350)","2","mstr_standard","I52";
;
CDS_LIB"mstr_standard"
BODY_TYPE"PLUMBING"
HDL_TAP"TRUE";
"B \NAC \NWC"3;
"S \NAC"
BN"59"25;
%"TAP"
"6","(-1700,4150)","2","mstr_standard","I53";
;
CDS_LIB"mstr_standard"
BODY_TYPE"PLUMBING"
HDL_TAP"TRUE";
"B \NAC \NWC"3;
"S \NAC"
BN"55"140;
%"TAP"
"6","(-1700,4200)","2","mstr_standard","I54";
;
CDS_LIB"mstr_standard"
BODY_TYPE"PLUMBING"
HDL_TAP"TRUE";
"B \NAC \NWC"3;
"S \NAC"
BN"54"142;
%"TAP"
"6","(-1700,4250)","2","mstr_standard","I55";
;
CDS_LIB"mstr_standard"
BODY_TYPE"PLUMBING"
HDL_TAP"TRUE";
"B \NAC \NWC"3;
"S \NAC"
BN"57"143;
%"TAP"
"6","(-1700,4050)","2","mstr_standard","I56";
;
CDS_LIB"mstr_standard"
BODY_TYPE"PLUMBING"
HDL_TAP"TRUE";
"B \NAC \NWC"3;
"S \NAC"
BN"53"120;
%"TAP"
"6","(-1700,4100)","2","mstr_standard","I57";
;
CDS_LIB"mstr_standard"
BODY_TYPE"PLUMBING"
HDL_TAP"TRUE";
"B \NAC \NWC"3;
"S \NAC"
BN"52"139;
%"TAP"
"6","(-1700,4000)","2","mstr_standard","I58";
;
CDS_LIB"mstr_standard"
BODY_TYPE"PLUMBING"
HDL_TAP"TRUE";
"B \NAC \NWC"3;
"S \NAC"
BN"50"119;
%"TAP"
"6","(-1700,3950)","2","mstr_standard","I59";
;
CDS_LIB"mstr_standard"
BODY_TYPE"PLUMBING"
HDL_TAP"TRUE";
"B \NAC \NWC"3;
"S \NAC"
BN"51"118;
%"TAP"
"6","(900,4900)","2","mstr_standard","I6";
;
CDS_LIB"mstr_standard"
BODY_TYPE"PLUMBING"
HDL_TAP"TRUE";
"B \NAC \NWC"2;
"S \NAC"
BN"15"26;
%"TAP"
"6","(-1700,3900)","2","mstr_standard","I60";
;
CDS_LIB"mstr_standard"
BODY_TYPE"PLUMBING"
HDL_TAP"TRUE";
"B \NAC \NWC"3;
"S \NAC"
BN"48"117;
%"SCONN288_H44441004"
"2","(0,4300)","0","mstr_sconn","I61";
;
CDS_SEC"2"
LOCATION"J4G2"
PART_NUMBER"H44441-004"
MATERIAL"SCONN"
PACK_TYPE"PIP"
BOM_COST"MEM"
CDS_LIB"mstr_sconn"
SEC_TYPE"PIP"
SEC"2"
CDS_LOCATION"J4G2"
ROOM"DDR4_CH_B";
"DQS17P"
$PN"51"176;
"DQS9P"
$PN"7"23;
"DQS9N"
$PN"8"160;
"DQS8P"
$PN"197"161;
"DQS8N"
$PN"196"162;
"DQS7P"
$PN"278"163;
"DQS7N"
$PN"277"164;
"DQS6P"
$PN"267"146;
"DQS6N"
$PN"266"147;
"DQS5P"
$PN"256"148;
"DQS5N"
$PN"255"149;
"DQS4P"
$PN"245"150;
"DQS4N"
$PN"244"151;
"DQS3P"
$PN"186"152;
"DQS3N"
$PN"185"153;
"DQS2P"
$PN"175"154;
"DQS2N"
$PN"174"155;
"DQS1P"
$PN"164"156;
"DQS1N"
$PN"163"157;
"DQS17N"
$PN"52"165;
"DQS16P"
$PN"132"166;
"DQS16N"
$PN"133"167;
"DQS15P"
$PN"121"168;
"DQS15N"
$PN"122"26;
"DQS14P"
$PN"110"169;
"DQS14N"
$PN"111"170;
"DQS13P"
$PN"99"27;
"DQS13N"
$PN"100"171;
"DQS12P"
$PN"40"172;
"DQS12N"
$PN"41"173;
"DQS11P"
$PN"29"174;
"DQS11N"
$PN"30"175;
"DQS10P"
$PN"18"22;
"DQS10N"
$PN"19"24;
"DQS0P"
$PN"153"158;
"DQS0N"
$PN"152"159;
%"TAP"
"6","(-1700,3750)","2","mstr_standard","I62";
;
CDS_LIB"mstr_standard"
BODY_TYPE"PLUMBING"
HDL_TAP"TRUE";
"B \NAC \NWC"3;
"S \NAC"
BN"47"124;
%"TAP"
"6","(-1700,3800)","2","mstr_standard","I63";
;
CDS_LIB"mstr_standard"
BODY_TYPE"PLUMBING"
HDL_TAP"TRUE";
"B \NAC \NWC"3;
"S \NAC"
BN"46"115;
%"TAP"
"6","(-1700,3850)","2","mstr_standard","I64";
;
CDS_LIB"mstr_standard"
BODY_TYPE"PLUMBING"
HDL_TAP"TRUE";
"B \NAC \NWC"3;
"S \NAC"
BN"49"116;
%"TAP"
"6","(-1700,3700)","2","mstr_standard","I65";
;
CDS_LIB"mstr_standard"
BODY_TYPE"PLUMBING"
HDL_TAP"TRUE";
"B \NAC \NWC"3;
"S \NAC"
BN"44"123;
%"TAP"
"6","(-1700,3650)","2","mstr_standard","I66";
;
CDS_LIB"mstr_standard"
BODY_TYPE"PLUMBING"
HDL_TAP"TRUE";
"B \NAC \NWC"3;
"S \NAC"
BN"45"122;
%"TAP"
"6","(-1700,3600)","2","mstr_standard","I67";
;
CDS_LIB"mstr_standard"
BODY_TYPE"PLUMBING"
HDL_TAP"TRUE";
"B \NAC \NWC"3;
"S \NAC"
BN"42"121;
%"TAP"
"6","(-1700,3550)","2","mstr_standard","I68";
;
CDS_LIB"mstr_standard"
BODY_TYPE"PLUMBING"
HDL_TAP"TRUE";
"B \NAC \NWC"3;
"S \NAC"
BN"43"114;
%"TAP"
"6","(-1700,3500)","2","mstr_standard","I69";
;
CDS_LIB"mstr_standard"
BODY_TYPE"PLUMBING"
HDL_TAP"TRUE";
"B \NAC \NWC"3;
"S \NAC"
BN"40"113;
%"TAP"
"6","(900,5000)","2","mstr_standard","I7";
;
CDS_LIB"mstr_standard"
BODY_TYPE"PLUMBING"
HDL_TAP"TRUE";
"B \NAC \NWC"2;
"S \NAC"
BN"16"167;
%"TAP"
"6","(-1700,3400)","2","mstr_standard","I70";
;
CDS_LIB"mstr_standard"
BODY_TYPE"PLUMBING"
HDL_TAP"TRUE";
"B \NAC \NWC"3;
"S \NAC"
BN"38"111;
%"TAP"
"6","(-1700,3450)","2","mstr_standard","I71";
;
CDS_LIB"mstr_standard"
BODY_TYPE"PLUMBING"
HDL_TAP"TRUE";
"B \NAC \NWC"3;
"S \NAC"
BN"41"112;
%"TAP"
"6","(-1700,3250)","2","mstr_standard","I72";
;
CDS_LIB"mstr_standard"
BODY_TYPE"PLUMBING"
HDL_TAP"TRUE";
"B \NAC \NWC"3;
"S \NAC"
BN"37"106;
%"TAP"
"6","(-1700,3300)","2","mstr_standard","I73";
;
CDS_LIB"mstr_standard"
BODY_TYPE"PLUMBING"
HDL_TAP"TRUE";
"B \NAC \NWC"3;
"S \NAC"
BN"36"110;
%"TAP"
"6","(-1700,3350)","2","mstr_standard","I74";
;
CDS_LIB"mstr_standard"
BODY_TYPE"PLUMBING"
HDL_TAP"TRUE";
"B \NAC \NWC"3;
"S \NAC"
BN"39"105;
%"TAP"
"6","(-1700,3150)","2","mstr_standard","I75";
;
CDS_LIB"mstr_standard"
BODY_TYPE"PLUMBING"
HDL_TAP"TRUE";
"B \NAC \NWC"3;
"S \NAC"
BN"35"109;
%"TAP"
"6","(-1700,3200)","2","mstr_standard","I76";
;
CDS_LIB"mstr_standard"
BODY_TYPE"PLUMBING"
HDL_TAP"TRUE";
"B \NAC \NWC"3;
"S \NAC"
BN"34"107;
%"TAP"
"6","(-1700,3100)","2","mstr_standard","I77";
;
CDS_LIB"mstr_standard"
BODY_TYPE"PLUMBING"
HDL_TAP"TRUE";
"B \NAC \NWC"3;
"S \NAC"
BN"32"108;
%"TAP"
"6","(-1700,3050)","2","mstr_standard","I78";
;
CDS_LIB"mstr_standard"
BODY_TYPE"PLUMBING"
HDL_TAP"TRUE";
"B \NAC \NWC"3;
"S \NAC"
BN"33"102;
%"TAP"
"6","(-1700,3000)","2","mstr_standard","I79";
;
CDS_LIB"mstr_standard"
BODY_TYPE"PLUMBING"
HDL_TAP"TRUE";
"B \NAC \NWC"3;
"S \NAC"
BN"30"101;
%"TAP"
"6","(900,4800)","2","mstr_standard","I8";
;
CDS_LIB"mstr_standard"
BODY_TYPE"PLUMBING"
HDL_TAP"TRUE";
"B \NAC \NWC"2;
"S \NAC"
BN"14"170;
%"TAP"
"6","(-1700,2850)","2","mstr_standard","I80";
;
CDS_LIB"mstr_standard"
BODY_TYPE"PLUMBING"
HDL_TAP"TRUE";
"B \NAC \NWC"3;
"S \NAC"
BN"29"103;
%"TAP"
"6","(-1700,2900)","2","mstr_standard","I81";
;
CDS_LIB"mstr_standard"
BODY_TYPE"PLUMBING"
HDL_TAP"TRUE";
"B \NAC \NWC"3;
"S \NAC"
BN"28"104;
%"TAP"
"6","(-1700,2950)","2","mstr_standard","I82";
;
CDS_LIB"mstr_standard"
BODY_TYPE"PLUMBING"
HDL_TAP"TRUE";
"B \NAC \NWC"3;
"S \NAC"
BN"31"100;
%"TAP"
"6","(-1700,2800)","2","mstr_standard","I83";
;
CDS_LIB"mstr_standard"
BODY_TYPE"PLUMBING"
HDL_TAP"TRUE";
"B \NAC \NWC"3;
"S \NAC"
BN"26"96;
%"TAP"
"6","(-1700,2750)","2","mstr_standard","I84";
;
CDS_LIB"mstr_standard"
BODY_TYPE"PLUMBING"
HDL_TAP"TRUE";
"B \NAC \NWC"3;
"S \NAC"
BN"27"95;
%"TAP"
"6","(-1700,2600)","2","mstr_standard","I85";
;
CDS_LIB"mstr_standard"
BODY_TYPE"PLUMBING"
HDL_TAP"TRUE";
"B \NAC \NWC"3;
"S \NAC"
BN"22"97;
%"TAP"
"6","(-1700,2700)","2","mstr_standard","I86";
;
CDS_LIB"mstr_standard"
BODY_TYPE"PLUMBING"
HDL_TAP"TRUE";
"B \NAC \NWC"3;
"S \NAC"
BN"24"99;
%"TAP"
"6","(-1700,2650)","2","mstr_standard","I87";
;
CDS_LIB"mstr_standard"
BODY_TYPE"PLUMBING"
HDL_TAP"TRUE";
"B \NAC \NWC"3;
"S \NAC"
BN"25"98;
%"TAP"
"6","(-1700,2500)","2","mstr_standard","I88";
;
CDS_LIB"mstr_standard"
BODY_TYPE"PLUMBING"
HDL_TAP"TRUE";
"B \NAC \NWC"3;
"S \NAC"
BN"20"92;
%"TAP"
"6","(-1700,2550)","2","mstr_standard","I89";
;
CDS_LIB"mstr_standard"
BODY_TYPE"PLUMBING"
HDL_TAP"TRUE";
"B \NAC \NWC"3;
"S \NAC"
BN"23"93;
%"TAP"
"6","(700,4950)","2","mstr_standard","I9";
;
CDS_LIB"mstr_standard"
BODY_TYPE"PLUMBING"
HDL_TAP"TRUE";
"B \NAC \NWC"1;
"S \NAC"
BN"15"168;
%"TAP"
"6","(-1700,2450)","2","mstr_standard","I90";
;
CDS_LIB"mstr_standard"
BODY_TYPE"PLUMBING"
HDL_TAP"TRUE";
"B \NAC \NWC"3;
"S \NAC"
BN"21"94;
%"TAP"
"6","(-1700,2400)","2","mstr_standard","I91";
;
CDS_LIB"mstr_standard"
BODY_TYPE"PLUMBING"
HDL_TAP"TRUE";
"B \NAC \NWC"3;
"S \NAC"
BN"18"91;
%"TAP"
"6","(-1700,2350)","2","mstr_standard","I92";
;
CDS_LIB"mstr_standard"
BODY_TYPE"PLUMBING"
HDL_TAP"TRUE";
"B \NAC \NWC"3;
"S \NAC"
BN"19"90;
%"TAP"
"6","(-1700,2250)","2","mstr_standard","I93";
;
CDS_LIB"mstr_standard"
BODY_TYPE"PLUMBING"
HDL_TAP"TRUE";
"B \NAC \NWC"3;
"S \NAC"
BN"17"89;
%"TAP"
"6","(-1700,2300)","2","mstr_standard","I94";
;
CDS_LIB"mstr_standard"
BODY_TYPE"PLUMBING"
HDL_TAP"TRUE";
"B \NAC \NWC"3;
"S \NAC"
BN"16"84;
%"TAP"
"6","(-1700,2100)","2","mstr_standard","I95";
;
CDS_LIB"mstr_standard"
BODY_TYPE"PLUMBING"
HDL_TAP"TRUE";
"B \NAC \NWC"3;
"S \NAC"
BN"12"87;
%"TAP"
"6","(-1700,2150)","2","mstr_standard","I96";
;
CDS_LIB"mstr_standard"
BODY_TYPE"PLUMBING"
HDL_TAP"TRUE";
"B \NAC \NWC"3;
"S \NAC"
BN"15"88;
%"TAP"
"6","(-1700,2200)","2","mstr_standard","I97";
;
CDS_LIB"mstr_standard"
BODY_TYPE"PLUMBING"
HDL_TAP"TRUE";
"B \NAC \NWC"3;
"S \NAC"
BN"14"85;
%"TAP"
"6","(-1700,2000)","2","mstr_standard","I98";
;
CDS_LIB"mstr_standard"
BODY_TYPE"PLUMBING"
HDL_TAP"TRUE";
"B \NAC \NWC"3;
"S \NAC"
BN"10"82;
%"TAP"
"6","(-1700,2050)","2","mstr_standard","I99";
;
CDS_LIB"mstr_standard"
BODY_TYPE"PLUMBING"
HDL_TAP"TRUE";
"B \NAC \NWC"3;
"S \NAC"
BN"13"86;
END.
